# T6G (Grand Teton) — schematic netlist excerpt (pin names and nets, part order shuffled) for the footprints in the layout excerpt that follows; sources: Cadence DE-HDL packaged netlist, KiCad conversion of 04192023_DAF0TMB3IC0_F0TG_MB_C_brd_V02_OCP.brd

X9005  TP_TDR_4P_FTS  TP_TDR_4P_DIP EMPTY  pkg TH  page 261
  S1  = TDR_DIFF_85_NECK_IN4_DP
  P1  = T1_GND
  P2  = T1_GND
  S2  = TDR_DIFF_85_NECK_IN4_DN

R8309  Q_RES  0 5% CHIP  pkg 0402LF  page 193 : A = SMB_SCM_2_R3_SDA ; B = PVDDCR_CPU0_P0_PMSDA_R

(kicad_pcb
	(version 20260206)
	(generator "pcbnew")
	(generator_version "10.0")
	(general
		(thickness 1.6)
		(legacy_teardrops no)
	)
	(paper "A4")
	(title_block
		(title "04192023_DAF0TMB3IC0_F0TG_MB_C_brd_V02_OCP.brd")
		(comment 1 "Grand Teton / footprints 5512-5513 of 8354")
	)
	(layers
		(0 "F.Cu" signal "TOP")
		(4 "In1.Cu" signal "GND")
		(6 "In2.Cu" signal "IN1")
		(8 "In3.Cu" signal "GND1")
		(10 "In4.Cu" signal "IN2")
		(12 "In5.Cu" signal "GND2")
		(14 "In6.Cu" signal "IN3")
		(16 "In7.Cu" signal "GND3")
		(18 "In8.Cu" signal "VCC")
		(20 "In9.Cu" signal "VCC1")
		(22 "In10.Cu" signal "GND4")
		(24 "In11.Cu" signal "IN4")
		(26 "In12.Cu" signal "GND5")
		(28 "In13.Cu" signal "IN5")
		(30 "In14.Cu" signal "GND6")
		(32 "In15.Cu" signal "IN6")
		(34 "In16.Cu" signal "GND7")
		(2 "B.Cu" signal "BOTTOM")
		(9 "F.Adhes" user "F.Adhesive")
		(11 "B.Adhes" user "B.Adhesive")
		(13 "F.Paste" user "Package Geometry/Pastemask Top")
		(15 "B.Paste" user "Package Geometry/Pastemask Bottom")
		(5 "F.SilkS" user "Ref Des/Silkscreen Top")
		(7 "B.SilkS" user "Ref Des/Silkscreen Bottom")
		(1 "F.Mask" user "Board Geometry/Soldermask Top")
		(3 "B.Mask" user "Board Geometry/Soldermask Bottom")
		(17 "Dwgs.User" user "User.Drawings")
		(19 "Cmts.User" user "User.Comments")
		(21 "Eco1.User" user "User.Eco1")
		(23 "Eco2.User" user "User.Eco2")
		(25 "Edge.Cuts" user "Board Geometry/Outline")
		(27 "Margin" user)
		(31 "F.CrtYd" user "Package Geometry/Place Bound Top")
		(29 "B.CrtYd" user "Package Geometry/Place Bound Bottom")
		(35 "F.Fab" user "Ref Des/Assembly Top")
		(33 "B.Fab" user "Ref Des/Assembly Bottom")
	)
	(footprint ""
		(layer "B.Cu")
		(at 508.971042 -306.911248 90)
		(property "Reference" "X9005"
			(at 4.62026 -1.55829 90)
			(unlocked yes)
			(layer "B.SilkS")
			(effects
				(font
					(size 0.7874 0.5842)
					(thickness 0.1524)
				)
				(justify left mirror)
			)
		)
		(property "Value" ""
			(at 0 0 90)
			(layer "B.Fab")
			(effects
				(font
					(size 1.27 1.27)
				)
				(justify mirror)
			)
		)
		(property "User Part Number" "N_A"
			(at -1.30175 1.27 0)
			(unlocked yes)
			(layer "Cmts.User")
			(hide yes)
			(effects
				(font
					(size 0.635 0.4064)
					(thickness 0.1524)
				)
				(justify mirror)
			)
		)
		(property "Device Type" "TP_TDR_4P_FTS_TH-TP_TDR_4P_DIP,EMPTY,TP15"
			(at -1.30175 1.27 0)
			(unlocked yes)
			(layer "B.Fab")
			(hide yes)
			(effects
				(font
					(size 0.635 0.4064)
					(thickness 0.1524)
				)
				(justify mirror)
			)
		)
		(duplicate_pad_numbers_are_jumpers no)
		(fp_line
			(start 0 -1.27)
			(end 0 -0.635)
			(stroke
				(width 0.1524)
				(type default)
			)
			(layer "B.SilkS")
		)
		(fp_line
			(start -2.54 -1.27)
			(end 0 -1.27)
			(stroke
				(width 0.1524)
				(type default)
			)
			(layer "B.SilkS")
		)
		(fp_line
			(start -2.54 -1.1303)
			(end -2.54 -1.27)
			(stroke
				(width 0.1524)
				(type default)
			)
			(layer "B.SilkS")
		)
		(fp_line
			(start 0 0.635)
			(end 0 1.905)
			(stroke
				(width 0.1524)
				(type default)
			)
			(layer "B.SilkS")
		)
		(fp_line
			(start -2.54 1.4097)
			(end -2.54 1.1303)
			(stroke
				(width 0.1524)
				(type default)
			)
			(layer "B.SilkS")
		)
		(fp_line
			(start 0 3.175)
			(end 0 3.81)
			(stroke
				(width 0.1524)
				(type default)
			)
			(layer "B.SilkS")
		)
		(fp_line
			(start 0 3.81)
			(end -2.54 3.81)
			(stroke
				(width 0.1524)
				(type default)
			)
			(layer "B.SilkS")
		)
		(fp_line
			(start -2.54 3.81)
			(end -2.54 3.6703)
			(stroke
				(width 0.1524)
				(type default)
			)
			(layer "B.SilkS")
		)
		(fp_poly
			(pts
				(xy 0.761746 0) (xy 2.285746 -0.762) (xy 2.285746 0.762)
			)
			(stroke
				(width 0)
				(type default)
			)
			(fill yes)
			(layer "B.SilkS")
		)
		(fp_line
			(start 0 -1.27)
			(end 0 3.81)
			(stroke
				(width 0.1)
				(type default)
			)
			(layer "B.Fab")
		)
		(fp_line
			(start -2.54 -1.27)
			(end 0 -1.27)
			(stroke
				(width 0.1)
				(type default)
			)
			(layer "B.Fab")
		)
		(fp_line
			(start 0 3.81)
			(end -2.54 3.81)
			(stroke
				(width 0.1)
				(type default)
			)
			(layer "B.Fab")
		)
		(fp_line
			(start -2.54 3.81)
			(end -2.54 -1.27)
			(stroke
				(width 0.1)
				(type default)
			)
			(layer "B.Fab")
		)
		(fp_poly
			(pts
				(xy 0.761746 0) (xy 2.285746 -0.762) (xy 2.285746 0.762)
			)
			(stroke
				(width 0)
				(type default)
			)
			(fill yes)
			(layer "B.Fab")
		)
		(pad "1" thru_hole circle
			(at 0 0 270)
			(size 1.0033 1.0033)
			(drill 0.249936)
			(layers "*.Cu" "*.Mask")
			(remove_unused_layers no)
			(net "TDR_DIFF_85_NECK_IN4_DP")
			(clearance 0.10795)
			(padstack
				(mode front_inner_back)
				(layer "Inner"
					(shape circle)
					(size 0.8001 0.8001)
					(clearance 0.1524)
				)
				(layer "B.Cu"
					(shape circle)
					(size 1.0033 1.0033)
					(thermal_gap 0.10795)
					(clearance 0.10795)
				)
			)
		)
		(pad "2" thru_hole circle
			(at -2.54 0 270)
			(size 1.9939 1.9939)
			(drill 0.249936)
			(layers "*.Cu" "*.Mask")
			(remove_unused_layers no)
			(net "T1_GND")
			(clearance 0.10795)
			(padstack
				(mode front_inner_back)
				(layer "Inner"
					(shape circle)
					(size 0.8001 0.8001)
					(clearance 0.1524)
				)
				(layer "B.Cu"
					(shape circle)
					(size 1.9939 1.9939)
					(thermal_gap 0.10795)
					(clearance 0.10795)
				)
			)
		)
		(pad "3" thru_hole circle
			(at -2.54 2.54 270)
			(size 1.9939 1.9939)
			(drill 0.249936)
			(layers "*.Cu" "*.Mask")
			(remove_unused_layers no)
			(net "T1_GND")
			(clearance 0.10795)
			(padstack
				(mode front_inner_back)
				(layer "Inner"
					(shape circle)
					(size 0.8001 0.8001)
					(clearance 0.1524)
				)
				(layer "B.Cu"
					(shape circle)
					(size 1.9939 1.9939)
					(thermal_gap 0.10795)
					(clearance 0.10795)
				)
			)
		)
		(pad "4" thru_hole circle
			(at 0 2.54 270)
			(size 1.0033 1.0033)
			(drill 0.249936)
			(layers "*.Cu" "*.Mask")
			(remove_unused_layers no)
			(net "TDR_DIFF_85_NECK_IN4_DN")
			(clearance 0.10795)
			(padstack
				(mode front_inner_back)
				(layer "Inner"
					(shape circle)
					(size 0.8001 0.8001)
					(clearance 0.1524)
				)
				(layer "B.Cu"
					(shape circle)
					(size 1.0033 1.0033)
					(thermal_gap 0.10795)
					(clearance 0.10795)
				)
			)
		)
	)
	(footprint ""
		(layer "B.Cu")
		(at 374.715278 -137.789158 -90)
		(property "Reference" "R8309"
			(at 0 0 90)
			(layer "B.SilkS")
			(hide yes)
			(effects
				(font
					(size 1.27 1.27)
				)
				(justify mirror)
			)
		)
		(property "Value" ""
			(at 0 0 90)
			(layer "B.Fab")
			(effects
				(font
					(size 1.27 1.27)
				)
				(justify mirror)
			)
		)
		(duplicate_pad_numbers_are_jumpers no)
		(fp_line
			(start -0.7874 0.4064)
			(end 0.7874 0.4064)
			(stroke
				(width 0.1524)
				(type default)
			)
			(layer "B.SilkS")
		)
		(fp_line
			(start 0.7874 0.4064)
			(end 0.7874 -0.4064)
			(stroke
				(width 0.1524)
				(type default)
			)
			(layer "B.SilkS")
		)
		(fp_line
			(start -0.7874 -0.4064)
			(end -0.7874 0.4064)
			(stroke
				(width 0.1524)
				(type default)
			)
			(layer "B.SilkS")
		)
		(fp_line
			(start 0.7874 -0.4064)
			(end -0.7874 -0.4064)
			(stroke
				(width 0.1524)
				(type default)
			)
			(layer "B.SilkS")
		)
		(fp_line
			(start -0.67945 0.3048)
			(end -0.120396 0.3048)
			(stroke
				(width 0.1)
				(type default)
			)
			(layer "B.Fab")
		)
		(fp_line
			(start -0.120396 0.3048)
			(end -0.120396 0.2794)
			(stroke
				(width 0.1)
				(type default)
			)
			(layer "B.Fab")
		)
		(fp_line
			(start 0.12065 0.3048)
			(end 0.67945 0.3048)
			(stroke
				(width 0.1)
				(type default)
			)
			(layer "B.Fab")
		)
		(fp_line
			(start 0.67945 0.3048)
			(end 0.67945 -0.305054)
			(stroke
				(width 0.1)
				(type default)
			)
			(layer "B.Fab")
		)
		(fp_line
			(start -0.120396 0.2794)
			(end 0.12065 0.2794)
			(stroke
				(width 0.1)
				(type default)
			)
			(layer "B.Fab")
		)
		(fp_line
			(start 0.12065 0.2794)
			(end 0.12065 0.3048)
			(stroke
				(width 0.1)
				(type default)
			)
			(layer "B.Fab")
		)
		(fp_line
			(start -0.12065 -0.2794)
			(end -0.12065 -0.3048)
			(stroke
				(width 0.1)
				(type default)
			)
			(layer "B.Fab")
		)
		(fp_line
			(start 0.12065 -0.2794)
			(end -0.12065 -0.2794)
			(stroke
				(width 0.1)
				(type default)
			)
			(layer "B.Fab")
		)
		(fp_line
			(start -0.67945 -0.3048)
			(end -0.67945 0.3048)
			(stroke
				(width 0.1)
				(type default)
			)
			(layer "B.Fab")
		)
		(fp_line
			(start -0.12065 -0.3048)
			(end -0.67945 -0.3048)
			(stroke
				(width 0.1)
				(type default)
			)
			(layer "B.Fab")
		)
		(fp_line
			(start 0.12065 -0.305054)
			(end 0.12065 -0.2794)
			(stroke
				(width 0.1)
				(type default)
			)
			(layer "B.Fab")
		)
		(fp_line
			(start 0.67945 -0.305054)
			(end 0.12065 -0.305054)
			(stroke
				(width 0.1)
				(type default)
			)
			(layer "B.Fab")
		)
		(pad "1" smd circle
			(at 0.40005 0 90)
			(size 0 0)
			(layers "B.Cu" "B.Mask" "B.Paste")
			(net "SMB_SCM_2_R3_SDA")
		)
		(pad "2" smd circle
			(at -0.40005 0 90)
			(size 0 0)
			(layers "B.Cu" "B.Mask" "B.Paste")
			(net "PVDDCR_CPU0_P0_PMSDA_R")
		)
	)
)
